(kicad_pcb
	(version 20260206)
	(generator "pcbnew")
	(generator_version "10.0")
	(general
		(thickness 1.6)
		(legacy_teardrops no)
	)
	(paper "A4")
	(title_block
		(title "04192023_DAF0TMB3IC0_F0TG_MB_C_brd_V02_OCP.brd")
		(comment 1 "Grand Teton / footprints 180-183 of 8354")
	)
	(layers
		(0 "F.Cu" signal "TOP")
		(4 "In1.Cu" signal "GND")
		(6 "In2.Cu" signal "IN1")
		(8 "In3.Cu" signal "GND1")
		(10 "In4.Cu" signal "IN2")
		(12 "In5.Cu" signal "GND2")
		(14 "In6.Cu" signal "IN3")
		(16 "In7.Cu" signal "GND3")
		(18 "In8.Cu" signal "VCC")
		(20 "In9.Cu" signal "VCC1")
		(22 "In10.Cu" signal "GND4")
		(24 "In11.Cu" signal "IN4")
		(26 "In12.Cu" signal "GND5")
		(28 "In13.Cu" signal "IN5")
		(30 "In14.Cu" signal "GND6")
		(32 "In15.Cu" signal "IN6")
		(34 "In16.Cu" signal "GND7")
		(2 "B.Cu" signal "BOTTOM")
		(9 "F.Adhes" user "F.Adhesive")
		(11 "B.Adhes" user "B.Adhesive")
		(13 "F.Paste" user "Package Geometry/Pastemask Top")
		(15 "B.Paste" user "Package Geometry/Pastemask Bottom")
		(5 "F.SilkS" user "Ref Des/Silkscreen Top")
		(7 "B.SilkS" user "Ref Des/Silkscreen Bottom")
		(1 "F.Mask" user "Board Geometry/Soldermask Top")
		(3 "B.Mask" user "Board Geometry/Soldermask Bottom")
		(17 "Dwgs.User" user "User.Drawings")
		(19 "Cmts.User" user "User.Comments")
		(21 "Eco1.User" user "User.Eco1")
		(23 "Eco2.User" user "User.Eco2")
		(25 "Edge.Cuts" user "Board Geometry/Outline")
		(27 "Margin" user)
		(31 "F.CrtYd" user "Package Geometry/Place Bound Top")
		(29 "B.CrtYd" user "Package Geometry/Place Bound Bottom")
		(35 "F.Fab" user "Ref Des/Assembly Top")
		(33 "B.Fab" user "Ref Des/Assembly Bottom")
	)
	(footprint ""
		(layer "F.Cu")
		(at 123.96597 -165.192456 180)
		(property "Reference" "PU31"
			(at 2.577592 -7.079742 0)
			(unlocked yes)
			(layer "F.SilkS")
			(effects
				(font
					(size 0.7874 0.5842)
					(thickness 0.1524)
				)
				(justify left)
			)
		)
		(property "Value" ""
			(at 0 0 180)
			(layer "F.Fab")
			(effects
				(font
					(size 1.27 1.27)
				)
			)
		)
		(duplicate_pad_numbers_are_jumpers no)
		(fp_line
			(start 2.500122 2.999994)
			(end 2.2987 2.999994)
			(stroke
				(width 0.1524)
				(type default)
			)
			(layer "F.SilkS")
		)
		(fp_line
			(start 2.500122 2.339594)
			(end 2.500122 2.999994)
			(stroke
				(width 0.1524)
				(type default)
			)
			(layer "F.SilkS")
		)
		(fp_line
			(start 2.500122 -2.999994)
			(end 2.500122 -2.44348)
			(stroke
				(width 0.1524)
				(type default)
			)
			(layer "F.SilkS")
		)
		(fp_line
			(start 2.31394 -2.999994)
			(end 2.500122 -2.999994)
			(stroke
				(width 0.1524)
				(type default)
			)
			(layer "F.SilkS")
		)
		(fp_line
			(start -2.2987 2.999994)
			(end -2.500122 2.999994)
			(stroke
				(width 0.1524)
				(type default)
			)
			(layer "F.SilkS")
		)
		(fp_line
			(start -2.500122 2.999994)
			(end -2.500122 2.339594)
			(stroke
				(width 0.1524)
				(type default)
			)
			(layer "F.SilkS")
		)
		(fp_line
			(start -2.500122 0.6604)
			(end -2.500122 0.229108)
			(stroke
				(width 0.1524)
				(type default)
			)
			(layer "F.SilkS")
		)
		(fp_line
			(start -2.500122 -2.529078)
			(end -2.500122 -2.999994)
			(stroke
				(width 0.1524)
				(type default)
			)
			(layer "F.SilkS")
		)
		(fp_line
			(start -2.500122 -2.999994)
			(end -2.24409 -2.999994)
			(stroke
				(width 0.1524)
				(type default)
			)
			(layer "F.SilkS")
		)
		(fp_poly
			(pts
				(xy -2.757424 -2.445004) (xy -3.431032 -2.66954) (xy -2.98196 -3.118612)
			)
			(stroke
				(width 0)
				(type default)
			)
			(fill yes)
			(layer "F.SilkS")
		)
		(fp_line
			(start 2.500122 2.999994)
			(end -2.500122 2.999994)
			(stroke
				(width 0.1)
				(type default)
			)
			(layer "F.Fab")
		)
		(fp_line
			(start 2.500122 -2.999994)
			(end 2.500122 2.999994)
			(stroke
				(width 0.1)
				(type default)
			)
			(layer "F.Fab")
		)
		(fp_line
			(start -2.500122 2.999994)
			(end -2.500122 -2.999994)
			(stroke
				(width 0.1)
				(type default)
			)
			(layer "F.Fab")
		)
		(fp_line
			(start -2.500122 -2.999994)
			(end 2.500122 -2.999994)
			(stroke
				(width 0.1)
				(type default)
			)
			(layer "F.Fab")
		)
		(fp_poly
			(pts
				(xy -4.218432 -2.783078) (xy -4.218432 -1.767078) (xy -3.202432 -2.275078)
			)
			(stroke
				(width 0)
				(type default)
			)
			(fill yes)
			(layer "F.Fab")
		)
		(pad "1" smd rect
			(at -2.400046 -2.275078 270)
			(size 0.2286 0.6096)
			(layers "F.Cu" "F.Mask" "F.Paste")
			(net "PVDDCR_SOC_P1_VOS2")
		)
		(pad "2" smd rect
			(at -2.400046 -1.82499 270)
			(size 0.2286 0.6096)
			(layers "F.Cu" "F.Mask" "F.Paste")
			(net "GND")
		)
		(pad "3" smd rect
			(at -2.400046 -1.374902 270)
			(size 0.2286 0.6096)
			(layers "F.Cu" "F.Mask" "F.Paste")
			(net "PVDDCR_SOC_P1_VCC2")
		)
		(pad "4" smd rect
			(at -2.400046 -0.925068 270)
			(size 0.2286 0.6096)
			(layers "F.Cu" "F.Mask" "F.Paste")
			(net "PVDDCR_CPU0_P1_PVCC")
		)
		(pad "5" smd rect
			(at -2.400046 -0.47498 270)
			(size 0.2286 0.6096)
			(layers "F.Cu" "F.Mask" "F.Paste")
			(net "GND")
		)
		(pad "6" smd rect
			(at -2.400046 -0.024892 270)
			(size 0.2286 0.6096)
			(layers "F.Cu" "F.Mask" "F.Paste")
			(net "NC_PVDDCR_SOC_P1_GL1_2")
		)
		(pad "7_9-20_24" smd circle
			(at 0 1.150112 270)
			(size 0 0)
			(layers "F.Cu" "F.Mask" "F.Paste")
			(net "GND")
		)
		(pad "10_19" smd rect
			(at 0 2.899918 270)
			(size 0.6096 4.318)
			(layers "F.Cu" "F.Mask" "F.Paste")
			(net "SW_PVDDCR_SOC_P1_SW2")
		)
		(pad "25_29" smd rect
			(at 1.549908 -1.279906 90)
			(size 2.0574 2.3114)
			(layers "F.Cu" "F.Mask" "F.Paste")
			(net "SW_P12V_AUX_PVDDCR_SOC_P1_FLT")
		)
		(pad "30" smd rect
			(at 2.05994 -2.899918 180)
			(size 0.2286 0.6096)
			(layers "F.Cu" "F.Mask" "F.Paste")
			(net "SW_P12V_AUX_PVDDCR_SOC_P1_FLT")
		)
		(pad "31" smd rect
			(at 1.610106 -2.899918 180)
			(size 0.2286 0.6096)
			(layers "F.Cu" "F.Mask" "F.Paste")
			(net "NC_PVDDCR_SOC_P1_DNC2")
		)
		(pad "32" smd rect
			(at 1.160018 -2.899918 180)
			(size 0.2286 0.6096)
			(layers "F.Cu" "F.Mask" "F.Paste")
			(net "SW_PVDDCR_SOC_P1_PH2")
		)
		(pad "33" smd rect
			(at 0.70993 -2.899918 180)
			(size 0.2286 0.6096)
			(layers "F.Cu" "F.Mask" "F.Paste")
			(net "SW_PVDDCR_SOC_P1_BOOT2")
		)
		(pad "34" smd rect
			(at 0.260096 -2.899918 180)
			(size 0.2286 0.6096)
			(layers "F.Cu" "F.Mask" "F.Paste")
			(net "PVDDCR_SOC_P1_PWM2")
		)
		(pad "35" smd rect
			(at -0.189992 -2.899918 180)
			(size 0.2286 0.6096)
			(layers "F.Cu" "F.Mask" "F.Paste")
			(net "PVDDCR_SOC_P1_VCC2")
		)
		(pad "36" smd rect
			(at -0.64008 -2.899918 180)
			(size 0.2286 0.6096)
			(layers "F.Cu" "F.Mask" "F.Paste")
			(net "PVDDCR_SOC_P1_TEMP1")
		)
		(pad "37" smd rect
			(at -1.089914 -2.899918 180)
			(size 0.2286 0.6096)
			(layers "F.Cu" "F.Mask" "F.Paste")
			(net "PVDDCR_SOC_P1_LSET2")
		)
		(pad "38" smd rect
			(at -1.540002 -2.899918 180)
			(size 0.2286 0.6096)
			(layers "F.Cu" "F.Mask" "F.Paste")
			(net "PVDDCR_SOC_P1_IMON2")
		)
		(pad "39" smd rect
			(at -1.99009 -2.899918 180)
			(size 0.2286 0.6096)
			(layers "F.Cu" "F.Mask" "F.Paste")
			(net "PVDDCR_CPU0_P1_VCCS")
		)
		(pad "40" smd rect
			(at -0.87503 -1.27508 180)
			(size 1.7526 1.9558)
			(layers "F.Cu" "F.Mask" "F.Paste")
			(net "GND")
		)
		(pad "41" smd rect
			(at -1.525016 0.249936 90)
			(size 0.3048 0.4572)
			(layers "F.Cu" "F.Mask" "F.Paste")
			(net "NC_PVDDCR_SOC_P1_GL2_2")
		)
		(zone
			(layer "F.Cu")
			(hatch none 0.5)
			(connect_pads
				(clearance 0)
			)
			(min_thickness 0.25)
			(keepout
				(tracks not_allowed)
				(vias allowed)
				(pads allowed)
				(copperpour not_allowed)
				(footprints allowed)
			)
			(placement
				(enabled no)
				(sheetname "")
			)
			(fill
				(thermal_gap 0.5)
				(thermal_bridge_width 0.5)
				(island_removal_mode 0)
			)
			(polygon
				(pts
					(xy 126.466092 -167.736774) (xy 126.466092 -167.44315) (xy 121.465848 -167.44315) (xy 121.465848 -167.736774)
					(xy 121.75617 -167.736774) (xy 126.17577 -167.736774)
				)
			)
		)
		(zone
			(layer "F.Cu")
			(hatch none 0.5)
			(connect_pads
				(clearance 0)
			)
			(min_thickness 0.25)
			(keepout
				(tracks not_allowed)
				(vias allowed)
				(pads allowed)
				(copperpour not_allowed)
				(footprints allowed)
			)
			(placement
				(enabled no)
				(sheetname "")
			)
			(fill
				(thermal_gap 0.5)
				(thermal_bridge_width 0.5)
				(island_removal_mode 0)
			)
			(polygon
				(pts
					(xy 123.9139 -164.946076) (xy 123.9139 -162.888676) (xy 125.7681 -162.888676) (xy 125.7681 -163.129722)
					(xy 126.010416 -163.129722) (xy 126.010416 -162.648138) (xy 122.131582 -162.648138) (xy 122.131582 -162.83305)
					(xy 123.622562 -162.83305) (xy 123.622562 -164.99205) (xy 121.465848 -164.99205) (xy 121.465848 -165.241732)
					(xy 123.618244 -165.241732)
				)
			)
		)
	)
	(footprint ""
		(layer "F.Cu")
		(at 193.089022 -24.091392 -90)
		(property "Reference" "R4015"
			(at 0 0 270)
			(layer "F.SilkS")
			(hide yes)
			(effects
				(font
					(size 1.27 1.27)
				)
			)
		)
		(property "Value" ""
			(at 0 0 270)
			(layer "F.Fab")
			(effects
				(font
					(size 1.27 1.27)
				)
			)
		)
		(duplicate_pad_numbers_are_jumpers no)
		(fp_line
			(start -0.7874 0.4064)
			(end -0.7874 -0.4064)
			(stroke
				(width 0.1524)
				(type default)
			)
			(layer "F.SilkS")
		)
		(fp_line
			(start 0.7874 0.4064)
			(end -0.7874 0.4064)
			(stroke
				(width 0.1524)
				(type default)
			)
			(layer "F.SilkS")
		)
		(fp_line
			(start -0.7874 -0.4064)
			(end 0.7874 -0.4064)
			(stroke
				(width 0.1524)
				(type default)
			)
			(layer "F.SilkS")
		)
		(fp_line
			(start 0.7874 -0.4064)
			(end 0.7874 0.4064)
			(stroke
				(width 0.1524)
				(type default)
			)
			(layer "F.SilkS")
		)
		(fp_line
			(start -0.67945 0.3048)
			(end -0.67945 -0.305054)
			(stroke
				(width 0.1)
				(type default)
			)
			(layer "F.Fab")
		)
		(fp_line
			(start -0.12065 0.3048)
			(end -0.67945 0.3048)
			(stroke
				(width 0.1)
				(type default)
			)
			(layer "F.Fab")
		)
		(fp_line
			(start 0.120396 0.3048)
			(end 0.120396 0.2794)
			(stroke
				(width 0.1)
				(type default)
			)
			(layer "F.Fab")
		)
		(fp_line
			(start 0.67945 0.3048)
			(end 0.120396 0.3048)
			(stroke
				(width 0.1)
				(type default)
			)
			(layer "F.Fab")
		)
		(fp_line
			(start -0.12065 0.2794)
			(end -0.12065 0.3048)
			(stroke
				(width 0.1)
				(type default)
			)
			(layer "F.Fab")
		)
		(fp_line
			(start 0.120396 0.2794)
			(end -0.12065 0.2794)
			(stroke
				(width 0.1)
				(type default)
			)
			(layer "F.Fab")
		)
		(fp_line
			(start -0.12065 -0.2794)
			(end 0.12065 -0.2794)
			(stroke
				(width 0.1)
				(type default)
			)
			(layer "F.Fab")
		)
		(fp_line
			(start 0.12065 -0.2794)
			(end 0.12065 -0.3048)
			(stroke
				(width 0.1)
				(type default)
			)
			(layer "F.Fab")
		)
		(fp_line
			(start 0.12065 -0.3048)
			(end 0.67945 -0.3048)
			(stroke
				(width 0.1)
				(type default)
			)
			(layer "F.Fab")
		)
		(fp_line
			(start 0.67945 -0.3048)
			(end 0.67945 0.3048)
			(stroke
				(width 0.1)
				(type default)
			)
			(layer "F.Fab")
		)
		(fp_line
			(start -0.67945 -0.305054)
			(end -0.12065 -0.305054)
			(stroke
				(width 0.1)
				(type default)
			)
			(layer "F.Fab")
		)
		(fp_line
			(start -0.12065 -0.305054)
			(end -0.12065 -0.2794)
			(stroke
				(width 0.1)
				(type default)
			)
			(layer "F.Fab")
		)
		(pad "1" smd circle
			(at -0.40005 0 270)
			(size 0 0)
			(layers "F.Cu" "F.Mask" "F.Paste")
			(net "P3V3_AUX")
		)
		(pad "2" smd circle
			(at 0.40005 0 270)
			(size 0 0)
			(layers "F.Cu" "F.Mask" "F.Paste")
			(net "HP_LVC3_SCM_HSC_PWRGD")
		)
	)
	(footprint ""
		(layer "F.Cu")
		(at 492.985044 -457.29398 90)
		(property "Reference" "X9009"
			(at -1.979168 1.12141 0)
			(unlocked yes)
			(layer "F.SilkS")
			(effects
				(font
					(size 0.7874 0.5842)
					(thickness 0.1524)
				)
				(justify left)
			)
		)
		(property "Value" ""
			(at 0 0 90)
			(layer "F.Fab")
			(effects
				(font
					(size 1.27 1.27)
				)
			)
		)
		(property "User Part Number" "N_A"
			(at 1.30175 1.27 180)
			(unlocked yes)
			(layer "Cmts.User")
			(hide yes)
			(effects
				(font
					(size 0.635 0.4064)
					(thickness 0.1524)
				)
			)
		)
		(property "Device Type" "TP_TDR_4P_FTS_TH-TP_TDR_4P_DIP,EMPTY,TP15"
			(at 1.30175 1.27 180)
			(unlocked yes)
			(layer "F.Fab")
			(hide yes)
			(effects
				(font
					(size 0.635 0.4064)
					(thickness 0.1524)
				)
			)
		)
		(duplicate_pad_numbers_are_jumpers no)
		(fp_line
			(start 2.54 -1.27)
			(end 0 -1.27)
			(stroke
				(width 0.1524)
				(type default)
			)
			(layer "F.SilkS")
		)
		(fp_line
			(start 0 -1.27)
			(end 0 -0.635)
			(stroke
				(width 0.1524)
				(type default)
			)
			(layer "F.SilkS")
		)
		(fp_line
			(start 2.54 -1.1303)
			(end 2.54 -1.27)
			(stroke
				(width 0.1524)
				(type default)
			)
			(layer "F.SilkS")
		)
		(fp_line
			(start 0 0.635)
			(end 0 1.905)
			(stroke
				(width 0.1524)
				(type default)
			)
			(layer "F.SilkS")
		)
		(fp_line
			(start 2.54 1.4097)
			(end 2.54 1.1303)
			(stroke
				(width 0.1524)
				(type default)
			)
			(layer "F.SilkS")
		)
		(fp_line
			(start 0 3.175)
			(end 0 3.81)
			(stroke
				(width 0.1524)
				(type default)
			)
			(layer "F.SilkS")
		)
		(fp_line
			(start 2.54 3.81)
			(end 2.54 3.6703)
			(stroke
				(width 0.1524)
				(type default)
			)
			(layer "F.SilkS")
		)
		(fp_line
			(start 0 3.81)
			(end 2.54 3.81)
			(stroke
				(width 0.1524)
				(type default)
			)
			(layer "F.SilkS")
		)
		(fp_poly
			(pts
				(xy -2.285746 -0.762) (xy -0.761746 0) (xy -2.285746 0.762)
			)
			(stroke
				(width 0)
				(type default)
			)
			(fill yes)
			(layer "F.SilkS")
		)
		(fp_line
			(start 2.54 -1.27)
			(end 0 -1.27)
			(stroke
				(width 0.1)
				(type default)
			)
			(layer "F.Fab")
		)
		(fp_line
			(start 0 -1.27)
			(end 0 3.81)
			(stroke
				(width 0.1)
				(type default)
			)
			(layer "F.Fab")
		)
		(fp_line
			(start 2.54 3.81)
			(end 2.54 -1.27)
			(stroke
				(width 0.1)
				(type default)
			)
			(layer "F.Fab")
		)
		(fp_line
			(start 0 3.81)
			(end 2.54 3.81)
			(stroke
				(width 0.1)
				(type default)
			)
			(layer "F.Fab")
		)
		(fp_poly
			(pts
				(xy -0.761746 0) (xy -2.285746 -0.762) (xy -2.285746 0.762)
			)
			(stroke
				(width 0)
				(type default)
			)
			(fill yes)
			(layer "F.Fab")
		)
		(pad "1" thru_hole circle
			(at 0 0 90)
			(size 1.0033 1.0033)
			(drill 0.249936)
			(layers "*.Cu" "*.Mask")
			(remove_unused_layers no)
			(net "TDR_DIFF_85_NECK_IN2_DN")
			(clearance 0.10795)
			(thermal_gap 0.10795)
			(padstack
				(mode front_inner_back)
				(layer "Inner"
					(shape circle)
					(size 0.8001 0.8001)
					(clearance 0.1524)
				)
				(layer "B.Cu"
					(shape circle)
					(size 1.0033 1.0033)
					(clearance 0.10795)
				)
			)
		)
		(pad "2" thru_hole circle
			(at 2.54 0 90)
			(size 1.9939 1.9939)
			(drill 0.249936)
			(layers "*.Cu" "*.Mask")
			(remove_unused_layers no)
			(net "T1_GND")
			(clearance 0.10795)
			(thermal_gap 0.10795)
			(padstack
				(mode front_inner_back)
				(layer "Inner"
					(shape circle)
					(size 0.8001 0.8001)
					(clearance 0.1524)
				)
				(layer "B.Cu"
					(shape circle)
					(size 1.9939 1.9939)
					(clearance 0.10795)
				)
			)
		)
		(pad "3" thru_hole circle
			(at 2.54 2.54 90)
			(size 1.9939 1.9939)
			(drill 0.249936)
			(layers "*.Cu" "*.Mask")
			(remove_unused_layers no)
			(net "T1_GND")
			(clearance 0.10795)
			(thermal_gap 0.10795)
			(padstack
				(mode front_inner_back)
				(layer "Inner"
					(shape circle)
					(size 0.8001 0.8001)
					(clearance 0.1524)
				)
				(layer "B.Cu"
					(shape circle)
					(size 1.9939 1.9939)
					(clearance 0.10795)
				)
			)
		)
		(pad "4" thru_hole circle
			(at 0 2.54 90)
			(size 1.0033 1.0033)
			(drill 0.249936)
			(layers "*.Cu" "*.Mask")
			(remove_unused_layers no)
			(net "TDR_DIFF_85_NECK_IN2_DP")
			(clearance 0.10795)
			(thermal_gap 0.10795)
			(padstack
				(mode front_inner_back)
				(layer "Inner"
					(shape circle)
					(size 0.8001 0.8001)
					(clearance 0.1524)
				)
				(layer "B.Cu"
					(shape circle)
					(size 1.0033 1.0033)
					(clearance 0.10795)
				)
			)
		)
	)
	(footprint ""
		(layer "F.Cu")
		(at 136.803638 -389.816086)
		(property "Reference" "R1429"
			(at 0 0 0)
			(layer "F.SilkS")
			(hide yes)
			(effects
				(font
					(size 1.27 1.27)
				)
			)
		)
		(property "Value" ""
			(at 0 0 0)
			(layer "F.Fab")
			(effects
				(font
					(size 1.27 1.27)
				)
			)
		)
		(duplicate_pad_numbers_are_jumpers no)
		(fp_line
			(start -0.32512 -0.175006)
			(end 0.32512 -0.175006)
			(stroke
				(width 0.1)
				(type default)
			)
			(layer "F.Fab")
		)
		(fp_line
			(start -0.32512 0.175006)
			(end -0.32512 -0.175006)
			(stroke
				(width 0.1)
				(type default)
			)
			(layer "F.Fab")
		)
		(fp_line
			(start 0.32512 -0.175006)
			(end 0.32512 0.175006)
			(stroke
				(width 0.1)
				(type default)
			)
			(layer "F.Fab")
		)
		(fp_line
			(start 0.32512 0.175006)
			(end -0.32512 0.175006)
			(stroke
				(width 0.1)
				(type default)
			)
			(layer "F.Fab")
		)
		(pad "1" smd rect
			(at -0.2667 0)
			(size 0.3048 0.381)
			(layers "F.Cu" "F.Mask" "F.Paste")
			(net "JTAG_TRST_RT_CPU1_P3_N")
		)
		(pad "2" smd rect
			(at 0.2667 0 180)
			(size 0.3048 0.381)
			(layers "F.Cu" "F.Mask" "F.Paste")
			(net "GND")
		)
	)
)
